(kicad_pcb
	(version 20260206)
	(generator "pcbnew")
	(generator_version "10.0")
	(general
		(thickness 1.6)
		(legacy_teardrops no)
	)
	(paper "A4")
	(title_block
		(title "Bryce Canyon_IOM_IOC_16318-2_OCP.brd")
		(comment 1 "Bryce Canyon / footprints 907-913 of 1605")
	)
	(layers
		(0 "F.Cu" signal "TOP")
		(4 "In1.Cu" signal "L2GND")
		(6 "In2.Cu" signal "L3")
		(8 "In3.Cu" signal "L4VCC")
		(10 "In4.Cu" signal "L5VCC")
		(12 "In5.Cu" signal "L6")
		(14 "In6.Cu" signal "L7GND")
		(2 "B.Cu" signal "BOTTOM")
		(9 "F.Adhes" user "F.Adhesive")
		(11 "B.Adhes" user "B.Adhesive")
		(13 "F.Paste" user "Package Geometry/Pastemask Top")
		(15 "B.Paste" user "Package Geometry/Pastemask Bottom")
		(5 "F.SilkS" user "Ref Des/Silkscreen Top")
		(7 "B.SilkS" user "Ref Des/Silkscreen Bottom")
		(1 "F.Mask" user "Board Geometry/Soldermask Top")
		(3 "B.Mask" user "Board Geometry/Soldermask Bottom")
		(17 "Dwgs.User" user "User.Drawings")
		(19 "Cmts.User" user "User.Comments")
		(21 "Eco1.User" user "User.Eco1")
		(23 "Eco2.User" user "User.Eco2")
		(25 "Edge.Cuts" user "Board Geometry/Outline")
		(27 "Margin" user)
		(31 "F.CrtYd" user "Package Geometry/Place Bound Top")
		(29 "B.CrtYd" user "Package Geometry/Place Bound Bottom")
		(35 "F.Fab" user "Ref Des/Assembly Top")
		(33 "B.Fab" user "Ref Des/Assembly Bottom")
	)
	(footprint ""
		(layer "F.Cu")
		(at 8.879332 -136.716516 90)
		(property "Reference" "R207"
			(at 0 0 90)
			(layer "F.SilkS")
			(hide yes)
			(effects
				(font
					(size 1.27 1.27)
				)
			)
		)
		(property "Value" "120R2F-GP"
			(at 0.064008 -3.993896 90)
			(unlocked yes)
			(layer "F.Fab")
			(hide yes)
			(effects
				(font
					(size 1.016 1.016)
					(thickness 0.1524)
				)
			)
		)
		(property "Device Type" "R402H16"
			(at 0.064008 -5.517896 90)
			(unlocked yes)
			(layer "F.Fab")
			(hide yes)
			(effects
				(font
					(size 1.016 1.016)
					(thickness 0.1524)
				)
			)
		)
		(duplicate_pad_numbers_are_jumpers no)
		(fp_line
			(start 0.508 -0.9398)
			(end -0.508 -0.9398)
			(stroke
				(width 0.1524)
				(type default)
			)
			(layer "F.SilkS")
		)
		(fp_line
			(start -0.508 -0.9398)
			(end -0.508 0.9398)
			(stroke
				(width 0.1524)
				(type default)
			)
			(layer "F.SilkS")
		)
		(fp_rect
			(start -0.508 0.9398)
			(end 0.508 -0.9398)
			(stroke
				(width 0)
				(type default)
			)
			(fill no)
			(layer "F.CrtYd")
		)
		(fp_rect
			(start -0.508 0.9398)
			(end 0.508 -0.9398)
			(stroke
				(width 0)
				(type default)
			)
			(fill no)
			(layer "F.Fab")
		)
		(pad "1" smd custom
			(at 0 -0.4445 90)
			(size 0.1397 0.1397)
			(layers "F.Cu" "F.Mask" "F.Paste")
			(net "GND")
			(options
				(clearance outline)
				(anchor circle)
			)
			(primitives
				(gr_poly
					(pts
						(arc
							(start -0.1778 -0.2794)
							(mid -0.249642 -0.249642)
							(end -0.2794 -0.1778)
						)
						(arc
							(start -0.2794 0.1778)
							(mid -0.249642 0.249642)
							(end -0.1778 0.2794)
						)
						(arc
							(start 0.1778 0.2794)
							(mid 0.249642 0.249642)
							(end 0.2794 0.1778)
						)
						(arc
							(start 0.2794 -0.1778)
							(mid 0.249642 -0.249642)
							(end 0.1778 -0.2794)
						)
					)
					(width 0)
					(fill yes)
				)
			)
		)
		(pad "2" smd custom
			(at 0 0.4445 90)
			(size 0.1397 0.1397)
			(layers "F.Cu" "F.Mask" "F.Paste")
			(net "DDR4_RST_N")
			(options
				(clearance outline)
				(anchor circle)
			)
			(primitives
				(gr_poly
					(pts
						(arc
							(start -0.1778 -0.2794)
							(mid -0.249642 -0.249642)
							(end -0.2794 -0.1778)
						)
						(arc
							(start -0.2794 0.1778)
							(mid -0.249642 0.249642)
							(end -0.1778 0.2794)
						)
						(arc
							(start 0.1778 0.2794)
							(mid 0.249642 0.249642)
							(end 0.2794 0.1778)
						)
						(arc
							(start 0.2794 -0.1778)
							(mid 0.249642 -0.249642)
							(end 0.1778 -0.2794)
						)
					)
					(width 0)
					(fill yes)
				)
			)
		)
	)
	(footprint ""
		(layer "F.Cu")
		(at 111.0742 -13.324078 -90)
		(property "Reference" "C149"
			(at 0 0 270)
			(layer "F.SilkS")
			(hide yes)
			(effects
				(font
					(size 1.27 1.27)
				)
			)
		)
		(property "Value" "SCD1U50V3KX-GP"
			(at 0 -2.8194 270)
			(unlocked yes)
			(layer "F.Fab")
			(hide yes)
			(effects
				(font
					(size 1.016 1.016)
					(thickness 0.1524)
				)
			)
		)
		(property "Device Type" "C603H36"
			(at 0 -4.3434 270)
			(unlocked yes)
			(layer "F.Fab")
			(hide yes)
			(effects
				(font
					(size 1.016 1.016)
					(thickness 0.1524)
				)
			)
		)
		(duplicate_pad_numbers_are_jumpers no)
		(fp_line
			(start 0.508 0)
			(end -0.508 0)
			(stroke
				(width 0.2032)
				(type default)
			)
			(layer "F.SilkS")
		)
		(fp_rect
			(start -0.5842 1.3335)
			(end 0.5842 -1.3335)
			(stroke
				(width 0)
				(type default)
			)
			(fill no)
			(layer "F.CrtYd")
		)
		(fp_rect
			(start -0.5842 1.3335)
			(end 0.5842 -1.3335)
			(stroke
				(width 0)
				(type default)
			)
			(fill no)
			(layer "F.Fab")
		)
		(pad "1" smd custom
			(at 0 -0.762 270)
			(size 0.2159 0.2159)
			(layers "F.Cu" "F.Mask" "F.Paste")
			(net "MB0_PSET_R")
			(options
				(clearance outline)
				(anchor circle)
			)
			(primitives
				(gr_poly
					(pts
						(arc
							(start -0.3302 -0.4318)
							(mid -0.402042 -0.402042)
							(end -0.4318 -0.3302)
						)
						(arc
							(start -0.4318 0.3302)
							(mid -0.402042 0.402042)
							(end -0.3302 0.4318)
						)
						(arc
							(start 0.3302 0.4318)
							(mid 0.402042 0.402042)
							(end 0.4318 0.3302)
						)
						(arc
							(start 0.4318 -0.3302)
							(mid 0.402042 -0.402042)
							(end 0.3302 -0.4318)
						)
					)
					(width 0)
					(fill yes)
				)
			)
		)
		(pad "2" smd custom
			(at 0 0.762 270)
			(size 0.2159 0.2159)
			(layers "F.Cu" "F.Mask" "F.Paste")
			(net "AGND_CURRENT_MON")
			(options
				(clearance outline)
				(anchor circle)
			)
			(primitives
				(gr_poly
					(pts
						(arc
							(start -0.3302 -0.4318)
							(mid -0.402042 -0.402042)
							(end -0.4318 -0.3302)
						)
						(arc
							(start -0.4318 0.3302)
							(mid -0.402042 0.402042)
							(end -0.3302 0.4318)
						)
						(arc
							(start 0.3302 0.4318)
							(mid 0.402042 0.402042)
							(end 0.4318 0.3302)
						)
						(arc
							(start 0.4318 -0.3302)
							(mid 0.402042 -0.402042)
							(end 0.3302 -0.4318)
						)
					)
					(width 0)
					(fill yes)
				)
			)
		)
	)
	(footprint ""
		(layer "F.Cu")
		(at 112.856264 -9.689338 -90)
		(property "Reference" "R462"
			(at 0 0 270)
			(layer "F.SilkS")
			(hide yes)
			(effects
				(font
					(size 1.27 1.27)
				)
			)
		)
		(property "Value" "22K6R2F-1-GP"
			(at 0.064008 -3.993896 270)
			(unlocked yes)
			(layer "F.Fab")
			(hide yes)
			(effects
				(font
					(size 1.016 1.016)
					(thickness 0.1524)
				)
			)
		)
		(property "Device Type" "R402H16"
			(at 0.064008 -5.517896 270)
			(unlocked yes)
			(layer "F.Fab")
			(hide yes)
			(effects
				(font
					(size 1.016 1.016)
					(thickness 0.1524)
				)
			)
		)
		(duplicate_pad_numbers_are_jumpers no)
		(fp_line
			(start -0.508 -0.9398)
			(end -0.508 0.9398)
			(stroke
				(width 0.1524)
				(type default)
			)
			(layer "F.SilkS")
		)
		(fp_line
			(start 0.508 -0.9398)
			(end -0.508 -0.9398)
			(stroke
				(width 0.1524)
				(type default)
			)
			(layer "F.SilkS")
		)
		(fp_rect
			(start -0.508 0.9398)
			(end 0.508 -0.9398)
			(stroke
				(width 0)
				(type default)
			)
			(fill no)
			(layer "F.CrtYd")
		)
		(fp_rect
			(start -0.508 0.9398)
			(end 0.508 -0.9398)
			(stroke
				(width 0)
				(type default)
			)
			(fill no)
			(layer "F.Fab")
		)
		(pad "1" smd custom
			(at 0 -0.4445 270)
			(size 0.1397 0.1397)
			(layers "F.Cu" "F.Mask" "F.Paste")
			(net "MB0_ISTART_R")
			(options
				(clearance outline)
				(anchor circle)
			)
			(primitives
				(gr_poly
					(pts
						(arc
							(start -0.1778 -0.2794)
							(mid -0.249642 -0.249642)
							(end -0.2794 -0.1778)
						)
						(arc
							(start -0.2794 0.1778)
							(mid -0.249642 0.249642)
							(end -0.1778 0.2794)
						)
						(arc
							(start 0.1778 0.2794)
							(mid 0.249642 0.249642)
							(end 0.2794 0.1778)
						)
						(arc
							(start 0.2794 -0.1778)
							(mid 0.249642 -0.249642)
							(end 0.1778 -0.2794)
						)
					)
					(width 0)
					(fill yes)
				)
			)
		)
		(pad "2" smd custom
			(at 0 0.4445 270)
			(size 0.1397 0.1397)
			(layers "F.Cu" "F.Mask" "F.Paste")
			(net "AGND_CURRENT_MON")
			(options
				(clearance outline)
				(anchor circle)
			)
			(primitives
				(gr_poly
					(pts
						(arc
							(start -0.1778 -0.2794)
							(mid -0.249642 -0.249642)
							(end -0.2794 -0.1778)
						)
						(arc
							(start -0.2794 0.1778)
							(mid -0.249642 0.249642)
							(end -0.1778 0.2794)
						)
						(arc
							(start 0.1778 0.2794)
							(mid 0.249642 0.249642)
							(end 0.2794 0.1778)
						)
						(arc
							(start 0.2794 -0.1778)
							(mid 0.249642 -0.249642)
							(end 0.1778 -0.2794)
						)
					)
					(width 0)
					(fill yes)
				)
			)
		)
	)
	(footprint ""
		(layer "F.Cu")
		(at 195.436236 -131.699 -90)
		(property "Reference" "R551"
			(at 0 0 270)
			(layer "F.SilkS")
			(hide yes)
			(effects
				(font
					(size 1.27 1.27)
				)
			)
		)
		(property "Value" "4K7R2F-GP"
			(at 0.064008 -3.993896 270)
			(unlocked yes)
			(layer "F.Fab")
			(hide yes)
			(effects
				(font
					(size 1.016 1.016)
					(thickness 0.1524)
				)
			)
		)
		(property "Device Type" "R402H16"
			(at 0.064008 -5.517896 270)
			(unlocked yes)
			(layer "F.Fab")
			(hide yes)
			(effects
				(font
					(size 1.016 1.016)
					(thickness 0.1524)
				)
			)
		)
		(duplicate_pad_numbers_are_jumpers no)
		(fp_line
			(start -0.508 -0.9398)
			(end -0.508 0.9398)
			(stroke
				(width 0.1524)
				(type default)
			)
			(layer "F.SilkS")
		)
		(fp_line
			(start 0.508 -0.9398)
			(end -0.508 -0.9398)
			(stroke
				(width 0.1524)
				(type default)
			)
			(layer "F.SilkS")
		)
		(fp_rect
			(start -0.508 0.9398)
			(end 0.508 -0.9398)
			(stroke
				(width 0)
				(type default)
			)
			(fill no)
			(layer "F.CrtYd")
		)
		(fp_rect
			(start -0.508 0.9398)
			(end 0.508 -0.9398)
			(stroke
				(width 0)
				(type default)
			)
			(fill no)
			(layer "F.Fab")
		)
		(pad "1" smd custom
			(at 0 -0.4445 270)
			(size 0.1397 0.1397)
			(layers "F.Cu" "F.Mask" "F.Paste")
			(net "P3V3_STBY")
			(options
				(clearance outline)
				(anchor circle)
			)
			(primitives
				(gr_poly
					(pts
						(arc
							(start -0.1778 -0.2794)
							(mid -0.249642 -0.249642)
							(end -0.2794 -0.1778)
						)
						(arc
							(start -0.2794 0.1778)
							(mid -0.249642 0.249642)
							(end -0.1778 0.2794)
						)
						(arc
							(start 0.1778 0.2794)
							(mid 0.249642 0.249642)
							(end 0.2794 0.1778)
						)
						(arc
							(start 0.2794 -0.1778)
							(mid 0.249642 -0.249642)
							(end 0.1778 -0.2794)
						)
					)
					(width 0)
					(fill yes)
				)
			)
		)
		(pad "2" smd custom
			(at 0 0.4445 270)
			(size 0.1397 0.1397)
			(layers "F.Cu" "F.Mask" "F.Paste")
			(net "Q8_G")
			(options
				(clearance outline)
				(anchor circle)
			)
			(primitives
				(gr_poly
					(pts
						(arc
							(start -0.1778 -0.2794)
							(mid -0.249642 -0.249642)
							(end -0.2794 -0.1778)
						)
						(arc
							(start -0.2794 0.1778)
							(mid -0.249642 0.249642)
							(end -0.1778 0.2794)
						)
						(arc
							(start 0.1778 0.2794)
							(mid 0.249642 0.249642)
							(end 0.2794 0.1778)
						)
						(arc
							(start 0.2794 -0.1778)
							(mid 0.249642 -0.249642)
							(end 0.1778 -0.2794)
						)
					)
					(width 0)
					(fill yes)
				)
			)
		)
	)
	(footprint ""
		(layer "F.Cu")
		(at 221.900242 -98.434652)
		(property "Reference" "C374"
			(at 0 0 0)
			(layer "F.SilkS")
			(hide yes)
			(effects
				(font
					(size 1.27 1.27)
				)
			)
		)
		(property "Value" "SC100U6D3V6MX-GP"
			(at -0.0762 -5.1308 0)
			(unlocked yes)
			(layer "F.Fab")
			(hide yes)
			(effects
				(font
					(size 1.016 1.016)
					(thickness 0.1524)
				)
			)
		)
		(property "Device Type" "C1206H71"
			(at -0.127 -6.6548 0)
			(unlocked yes)
			(layer "F.Fab")
			(hide yes)
			(effects
				(font
					(size 1.016 1.016)
					(thickness 0.1524)
				)
			)
		)
		(duplicate_pad_numbers_are_jumpers no)
		(fp_line
			(start -1.016 -2.2352)
			(end 1.016 -2.2352)
			(stroke
				(width 0.1524)
				(type default)
			)
			(layer "F.SilkS")
		)
		(fp_line
			(start -1.016 -0.8382)
			(end -1.016 -2.2352)
			(stroke
				(width 0.1524)
				(type default)
			)
			(layer "F.SilkS")
		)
		(fp_line
			(start -1.016 2.2352)
			(end -1.016 0.8382)
			(stroke
				(width 0.1524)
				(type default)
			)
			(layer "F.SilkS")
		)
		(fp_line
			(start 1.016 -2.2352)
			(end 1.016 -0.8382)
			(stroke
				(width 0.1524)
				(type default)
			)
			(layer "F.SilkS")
		)
		(fp_line
			(start 1.016 0.8382)
			(end 1.016 2.2352)
			(stroke
				(width 0.1524)
				(type default)
			)
			(layer "F.SilkS")
		)
		(fp_line
			(start 1.016 2.2352)
			(end -1.016 2.2352)
			(stroke
				(width 0.1524)
				(type default)
			)
			(layer "F.SilkS")
		)
		(fp_rect
			(start -1.0922 2.3114)
			(end 1.0922 -2.3114)
			(stroke
				(width 0)
				(type default)
			)
			(fill no)
			(layer "F.CrtYd")
		)
		(fp_poly
			(pts
				(xy 1.0922 -2.3114) (xy 1.0922 2.3114) (xy -1.0922 2.3114) (xy -1.0922 -2.3114)
			)
			(stroke
				(width 0)
				(type default)
			)
			(fill no)
			(layer "F.Fab")
		)
		(pad "1" smd rect
			(at 0 -1.397)
			(size 1.651 1.27)
			(layers "F.Cu" "F.Mask" "F.Paste")
			(net "GND")
		)
		(pad "2" smd rect
			(at 0 1.397)
			(size 1.651 1.27)
			(layers "F.Cu" "F.Mask" "F.Paste")
			(net "SAS0_AVDD")
		)
	)
	(footprint ""
		(layer "F.Cu")
		(at 185.845704 -149.714966 180)
		(property "Reference" "R474"
			(at 0 0 180)
			(layer "F.SilkS")
			(hide yes)
			(effects
				(font
					(size 1.27 1.27)
				)
			)
		)
		(property "Value" "73K2R2F-GP"
			(at 0.064008 -3.993896 180)
			(unlocked yes)
			(layer "F.Fab")
			(hide yes)
			(effects
				(font
					(size 1.016 1.016)
					(thickness 0.1524)
				)
			)
		)
		(property "Device Type" "R402H16"
			(at 0.064008 -5.517896 180)
			(unlocked yes)
			(layer "F.Fab")
			(hide yes)
			(effects
				(font
					(size 1.016 1.016)
					(thickness 0.1524)
				)
			)
		)
		(duplicate_pad_numbers_are_jumpers no)
		(fp_line
			(start 0.508 -0.9398)
			(end -0.508 -0.9398)
			(stroke
				(width 0.1524)
				(type default)
			)
			(layer "F.SilkS")
		)
		(fp_line
			(start -0.508 -0.9398)
			(end -0.508 0.9398)
			(stroke
				(width 0.1524)
				(type default)
			)
			(layer "F.SilkS")
		)
		(fp_rect
			(start -0.508 0.9398)
			(end 0.508 -0.9398)
			(stroke
				(width 0)
				(type default)
			)
			(fill no)
			(layer "F.CrtYd")
		)
		(fp_rect
			(start -0.508 0.9398)
			(end 0.508 -0.9398)
			(stroke
				(width 0)
				(type default)
			)
			(fill no)
			(layer "F.Fab")
		)
		(pad "1" smd custom
			(at 0 -0.4445 180)
			(size 0.1397 0.1397)
			(layers "F.Cu" "F.Mask" "F.Paste")
			(net "P5V_VFB")
			(options
				(clearance outline)
				(anchor circle)
			)
			(primitives
				(gr_poly
					(pts
						(arc
							(start -0.1778 -0.2794)
							(mid -0.249642 -0.249642)
							(end -0.2794 -0.1778)
						)
						(arc
							(start -0.2794 0.1778)
							(mid -0.249642 0.249642)
							(end -0.1778 0.2794)
						)
						(arc
							(start 0.1778 0.2794)
							(mid 0.249642 0.249642)
							(end 0.2794 0.1778)
						)
						(arc
							(start 0.2794 -0.1778)
							(mid 0.249642 -0.249642)
							(end 0.1778 -0.2794)
						)
					)
					(width 0)
					(fill yes)
				)
			)
		)
		(pad "2" smd custom
			(at 0 0.4445 180)
			(size 0.1397 0.1397)
			(layers "F.Cu" "F.Mask" "F.Paste")
			(net "P5V_VFB_R")
			(options
				(clearance outline)
				(anchor circle)
			)
			(primitives
				(gr_poly
					(pts
						(arc
							(start -0.1778 -0.2794)
							(mid -0.249642 -0.249642)
							(end -0.2794 -0.1778)
						)
						(arc
							(start -0.2794 0.1778)
							(mid -0.249642 0.249642)
							(end -0.1778 0.2794)
						)
						(arc
							(start 0.1778 0.2794)
							(mid 0.249642 0.249642)
							(end 0.2794 0.1778)
						)
						(arc
							(start 0.2794 -0.1778)
							(mid 0.249642 -0.249642)
							(end 0.1778 -0.2794)
						)
					)
					(width 0)
					(fill yes)
				)
			)
		)
	)
	(footprint ""
		(layer "F.Cu")
		(at 192.02908 -32.13354 90)
		(property "Reference" "R39"
			(at 0 0 90)
			(layer "F.SilkS")
			(hide yes)
			(effects
				(font
					(size 1.27 1.27)
				)
			)
		)
		(property "Value" "1MR2F-GP"
			(at 0.064008 -3.993896 90)
			(unlocked yes)
			(layer "F.Fab")
			(hide yes)
			(effects
				(font
					(size 1.016 1.016)
					(thickness 0.1524)
				)
			)
		)
		(property "Device Type" "R402H16"
			(at 0.064008 -5.517896 90)
			(unlocked yes)
			(layer "F.Fab")
			(hide yes)
			(effects
				(font
					(size 1.016 1.016)
					(thickness 0.1524)
				)
			)
		)
		(duplicate_pad_numbers_are_jumpers no)
		(fp_line
			(start 0.508 -0.9398)
			(end -0.508 -0.9398)
			(stroke
				(width 0.1524)
				(type default)
			)
			(layer "F.SilkS")
		)
		(fp_line
			(start -0.508 -0.9398)
			(end -0.508 0.9398)
			(stroke
				(width 0.1524)
				(type default)
			)
			(layer "F.SilkS")
		)
		(fp_rect
			(start -0.508 0.9398)
			(end 0.508 -0.9398)
			(stroke
				(width 0)
				(type default)
			)
			(fill no)
			(layer "F.CrtYd")
		)
		(fp_rect
			(start -0.508 0.9398)
			(end 0.508 -0.9398)
			(stroke
				(width 0)
				(type default)
			)
			(fill no)
			(layer "F.Fab")
		)
		(pad "1" smd custom
			(at 0 -0.4445 90)
			(size 0.1397 0.1397)
			(layers "F.Cu" "F.Mask" "F.Paste")
			(net "EXT1_CONN_GND")
			(options
				(clearance outline)
				(anchor circle)
			)
			(primitives
				(gr_poly
					(pts
						(arc
							(start -0.1778 -0.2794)
							(mid -0.249642 -0.249642)
							(end -0.2794 -0.1778)
						)
						(arc
							(start -0.2794 0.1778)
							(mid -0.249642 0.249642)
							(end -0.1778 0.2794)
						)
						(arc
							(start 0.1778 0.2794)
							(mid 0.249642 0.249642)
							(end 0.2794 0.1778)
						)
						(arc
							(start 0.2794 -0.1778)
							(mid 0.249642 -0.249642)
							(end 0.1778 -0.2794)
						)
					)
					(width 0)
					(fill yes)
				)
			)
		)
		(pad "2" smd custom
			(at 0 0.4445 90)
			(size 0.1397 0.1397)
			(layers "F.Cu" "F.Mask" "F.Paste")
			(net "GND")
			(options
				(clearance outline)
				(anchor circle)
			)
			(primitives
				(gr_poly
					(pts
						(arc
							(start -0.1778 -0.2794)
							(mid -0.249642 -0.249642)
							(end -0.2794 -0.1778)
						)
						(arc
							(start -0.2794 0.1778)
							(mid -0.249642 0.249642)
							(end -0.1778 0.2794)
						)
						(arc
							(start 0.1778 0.2794)
							(mid 0.249642 0.249642)
							(end 0.2794 0.1778)
						)
						(arc
							(start 0.2794 -0.1778)
							(mid 0.249642 -0.249642)
							(end 0.1778 -0.2794)
						)
					)
					(width 0)
					(fill yes)
				)
			)
		)
	)
)
